(kicad_pcb
	(version 20241229)
	(generator "pcbnew")
	(generator_version "9.0")
	(general
		(thickness 1.6)
		(legacy_teardrops no)
	)
	(paper "A4")
	(title_block
		(title "GMSL Deserializer")
		(date "2025-10-09")
		(rev "1.0.4")
		(company "Antmicro Ltd")
		(comment 1 "www.antmicro.com")
		(comment 9 "footprints 44-48 of 235")
	)
	(layers
		(0 "F.Cu" signal)
		(4 "In1.Cu" power)
		(6 "In2.Cu" power)
		(2 "B.Cu" signal)
		(9 "F.Adhes" user "F.Adhesive")
		(11 "B.Adhes" user "B.Adhesive")
		(13 "F.Paste" user)
		(15 "B.Paste" user)
		(5 "F.SilkS" user "F.Silkscreen")
		(7 "B.SilkS" user "B.Silkscreen")
		(1 "F.Mask" user)
		(3 "B.Mask" user)
		(17 "Dwgs.User" user "User.Drawings")
		(19 "Cmts.User" user "User.Comments")
		(21 "Eco1.User" user "User.Eco1")
		(23 "Eco2.User" user "User.Eco2")
		(25 "Edge.Cuts" user)
		(27 "Margin" user)
		(31 "F.CrtYd" user "F.Courtyard")
		(29 "B.CrtYd" user "B.Courtyard")
		(35 "F.Fab" user)
		(33 "B.Fab" user)
	)
	(footprint "antmicro-footprints:LED_0603_1608Metric_G"
		(layer "F.Cu")
		(at 150.876 96.11 -90)
		(descr "LED SMD 0603 Green")
		(tags "LED SMD 0603 Green")
		(property "Reference" "D16"
			(at -2.704444 32.459333 0)
			(layer "F.SilkS")
			(effects
				(font
					(size 0.7 0.7)
					(thickness 0.15)
				)
				(justify right bottom)
			)
		)
		(property "Value" "LED_G_0603_LTST-C190GKT"
			(at -0.001 1.599 90)
			(layer "F.Fab")
			(effects
				(font
					(size 0.7 0.7)
					(thickness 0.15)
				)
				(justify right bottom)
			)
		)
		(property "Datasheet" "https://media.digikey.com/pdf/Data%20Sheets/Lite-On%20PDFs/LTST-C190GKT.pdf"
			(at 0 0 270)
			(layer "F.Fab")
			(hide yes)
			(effects
				(font
					(size 1.27 1.27)
					(thickness 0.15)
				)
			)
		)
		(property "Description" "LED, Green, SMD, 0603, 20 mA, 2.1 V, 569 nm"
			(at 0 0 270)
			(layer "F.Fab")
			(hide yes)
			(effects
				(font
					(size 1.27 1.27)
					(thickness 0.15)
				)
			)
		)
		(property "Author" "Antmicro"
			(at 54.766 246.986 0)
			(layer "F.Fab")
			(hide yes)
			(effects
				(font
					(size 1 1)
					(thickness 0.15)
				)
			)
		)
		(property "Color" "Green"
			(at 54.766 246.986 0)
			(layer "F.Fab")
			(hide yes)
			(effects
				(font
					(size 1 1)
					(thickness 0.15)
				)
			)
		)
		(property "License" "Apache-2.0"
			(at 54.766 246.986 0)
			(layer "F.Fab")
			(hide yes)
			(effects
				(font
					(size 1 1)
					(thickness 0.15)
				)
			)
		)
		(property "MPN" "LTST-C190GKT"
			(at 54.766 246.986 0)
			(layer "F.Fab")
			(hide yes)
			(effects
				(font
					(size 1 1)
					(thickness 0.15)
				)
			)
		)
		(property "Manufacturer" "Lite-On"
			(at 54.766 246.986 0)
			(layer "F.Fab")
			(hide yes)
			(effects
				(font
					(size 1 1)
					(thickness 0.15)
				)
			)
		)
		(property "VSD_class" "LED"
			(at 54.766 246.986 0)
			(layer "F.Fab")
			(hide yes)
			(effects
				(font
					(size 1 1)
					(thickness 0.15)
				)
			)
		)
		(sheetname "/Power/")
		(sheetfile "power.kicad_sch")
		(attr smd)
		(fp_line
			(start 0.22 0.35)
			(end -0.22 0.35)
			(stroke
				(width 0.15)
				(type solid)
			)
			(layer "F.SilkS")
		)
		(fp_line
			(start -0.094672 0.201008)
			(end -0.094672 -0.198992)
			(stroke
				(width 0.1)
				(type solid)
			)
			(layer "F.SilkS")
		)
		(fp_line
			(start 0.105328 0.201008)
			(end -0.094672 0.001008)
			(stroke
				(width 0.1)
				(type solid)
			)
			(layer "F.SilkS")
		)
		(fp_line
			(start 0.105328 0.201008)
			(end 0.105328 -0.198992)
			(stroke
				(width 0.1)
				(type solid)
			)
			(layer "F.SilkS")
		)
		(fp_line
			(start -0.094672 0.001008)
			(end -0.24 0.001008)
			(stroke
				(width 0.1)
				(type solid)
			)
			(layer "F.SilkS")
		)
		(fp_line
			(start -0.094672 0.001008)
			(end 0.105328 -0.198992)
			(stroke
				(width 0.1)
				(type solid)
			)
			(layer "F.SilkS")
		)
		(fp_line
			(start 0.105328 0.001008)
			(end 0.24 0.001)
			(stroke
				(width 0.1)
				(type solid)
			)
			(layer "F.SilkS")
		)
		(fp_line
			(start -1.18 -0.319)
			(end -1.18 0.321)
			(stroke
				(width 0.15)
				(type solid)
			)
			(layer "F.SilkS")
		)
		(fp_line
			(start 0.22 -0.35)
			(end -0.22 -0.35)
			(stroke
				(width 0.15)
				(type solid)
			)
			(layer "F.SilkS")
		)
		(fp_rect
			(start 1.25 0.65)
			(end -1.25 -0.65)
			(stroke
				(width 0.05)
				(type solid)
			)
			(fill no)
			(layer "F.CrtYd")
		)
		(fp_line
			(start -0.199 0.2)
			(end -0.199 0.1)
			(stroke
				(width 0.15)
				(type solid)
			)
			(layer "F.Fab")
		)
		(fp_line
			(start 0.201 0.2)
			(end 0.201 0)
			(stroke
				(width 0.15)
				(type solid)
			)
			(layer "F.Fab")
		)
		(fp_line
			(start -0.199 0)
			(end -0.597 0)
			(stroke
				(width 0.15)
				(type solid)
			)
			(layer "F.Fab")
		)
		(fp_line
			(start -0.101 0)
			(end 0.201 0.2)
			(stroke
				(width 0.15)
				(type solid)
			)
			(layer "F.Fab")
		)
		(fp_line
			(start 0.201 0)
			(end 0.201 -0.202)
			(stroke
				(width 0.15)
				(type solid)
			)
			(layer "F.Fab")
		)
		(fp_line
			(start 0.599 0)
			(end 0.201 0)
			(stroke
				(width 0.15)
				(type solid)
			)
			(layer "F.Fab")
		)
		(fp_line
			(start -0.199 -0.202)
			(end -0.199 0.1)
			(stroke
				(width 0.15)
				(type solid)
			)
			(layer "F.Fab")
		)
		(fp_line
			(start 0.201 -0.202)
			(end -0.101 0)
			(stroke
				(width 0.15)
				(type solid)
			)
			(layer "F.Fab")
		)
		(fp_rect
			(start 0.848 0.4)
			(end -0.85 -0.402)
			(stroke
				(width 0.15)
				(type solid)
			)
			(fill no)
			(layer "F.Fab")
		)
		(pad "1" smd roundrect
			(at -0.7 0 90)
			(size 0.8 1)
			(layers "F.Cu" "F.Mask" "F.Paste")
			(roundrect_rratio 0.2)
			(net 140 "Net-(D16-C)")
			(pinfunction "C")
			(pintype "passive")
		)
		(pad "2" smd roundrect
			(at 0.7 0 90)
			(size 0.8 1)
			(layers "F.Cu" "F.Mask" "F.Paste")
			(roundrect_rratio 0.2)
			(net 5 "+5V")
			(pinfunction "A")
			(pintype "passive")
		)
	)
	(footprint "antmicro-footprints:C_0402_1005Metric"
		(layer "F.Cu")
		(at 145.724 66.5485 90)
		(descr "Capacitor SMD 0402")
		(tags "capacitor SMD 0402")
		(property "Reference" "C12"
			(at -1.8537 -0.563 90)
			(layer "F.SilkS")
			(effects
				(font
					(size 0.7 0.7)
					(thickness 0.15)
				)
				(justify left bottom)
			)
		)
		(property "Value" "C_10n_0402"
			(at -1.022927 2.155213 90)
			(layer "F.Fab")
			(effects
				(font
					(size 0.7 0.7)
					(thickness 0.15)
				)
				(justify left bottom)
			)
		)
		(property "Datasheet" "https://www.murata.com/products/productdetail?partno=GRM155R71H103KA88%23"
			(at 0 0 90)
			(layer "F.Fab")
			(hide yes)
			(effects
				(font
					(size 1.27 1.27)
					(thickness 0.15)
				)
			)
		)
		(property "Description" "SMD Multilayer Ceramic Capacitor, 10000 pF, 50 V, 0402 [1005 Metric], ± 10%, X7R, GRM Series"
			(at 0 0 90)
			(layer "F.Fab")
			(hide yes)
			(effects
				(font
					(size 1.27 1.27)
					(thickness 0.15)
				)
			)
		)
		(property "Author" "Antmicro"
			(at 212.2725 -79.1755 0)
			(layer "F.Fab")
			(hide yes)
			(effects
				(font
					(size 1 1)
					(thickness 0.15)
				)
			)
		)
		(property "Dielectric" "X7R"
			(at 212.2725 -79.1755 0)
			(layer "F.Fab")
			(hide yes)
			(effects
				(font
					(size 1 1)
					(thickness 0.15)
				)
			)
		)
		(property "License" "Apache-2.0"
			(at 212.2725 -79.1755 0)
			(layer "F.Fab")
			(hide yes)
			(effects
				(font
					(size 1 1)
					(thickness 0.15)
				)
			)
		)
		(property "MPN" "GRM155R71H103KA88D"
			(at 212.2725 -79.1755 0)
			(layer "F.Fab")
			(hide yes)
			(effects
				(font
					(size 1 1)
					(thickness 0.15)
				)
			)
		)
		(property "Manufacturer" "Murata"
			(at 212.2725 -79.1755 0)
			(layer "F.Fab")
			(hide yes)
			(effects
				(font
					(size 1 1)
					(thickness 0.15)
				)
			)
		)
		(property "Val" "10n"
			(at 212.2725 -79.1755 0)
			(layer "F.Fab")
			(hide yes)
			(effects
				(font
					(size 1 1)
					(thickness 0.15)
				)
			)
		)
		(property "Voltage" "50V"
			(at 212.2725 -79.1755 0)
			(layer "F.Fab")
			(hide yes)
			(effects
				(font
					(size 1 1)
					(thickness 0.15)
				)
			)
		)
		(sheetname "/Power/")
		(sheetfile "power.kicad_sch")
		(attr smd)
		(fp_rect
			(start -0.925 -0.47)
			(end 0.925 0.47)
			(stroke
				(width 0.05)
				(type default)
			)
			(fill no)
			(layer "F.CrtYd")
		)
		(fp_line
			(start 0.504 -0.25)
			(end 0.504 0.248)
			(stroke
				(width 0.15)
				(type solid)
			)
			(layer "F.Fab")
		)
		(fp_line
			(start -0.494 -0.25)
			(end 0.504 -0.25)
			(stroke
				(width 0.15)
				(type solid)
			)
			(layer "F.Fab")
		)
		(fp_line
			(start 0.504 0.248)
			(end -0.494 0.248)
			(stroke
				(width 0.15)
				(type solid)
			)
			(layer "F.Fab")
		)
		(fp_line
			(start -0.494 0.248)
			(end -0.494 -0.25)
			(stroke
				(width 0.15)
				(type solid)
			)
			(layer "F.Fab")
		)
		(pad "1" smd roundrect
			(at -0.48 0 90)
			(size 0.59 0.64)
			(layers "F.Cu" "F.Mask" "F.Paste")
			(roundrect_rratio 0.25)
			(net 1 "GND")
			(pintype "passive")
		)
		(pad "2" smd roundrect
			(at 0.48 0 90)
			(size 0.59 0.64)
			(layers "F.Cu" "F.Mask" "F.Paste")
			(roundrect_rratio 0.25)
			(net 4 "+12V")
			(pintype "passive")
		)
	)
	(footprint "antmicro-footprints:SOD-523_NP"
		(layer "F.Cu")
		(at 179.705 66.802 90)
		(property "Reference" "D10"
			(at -7.874 0.381 90)
			(layer "F.SilkS")
			(effects
				(font
					(size 0.7 0.7)
					(thickness 0.15)
				)
				(justify right bottom)
			)
		)
		(property "Value" "ESD5B5_0ST1G"
			(at 0 1.499 90)
			(layer "F.Fab")
			(effects
				(font
					(size 0.7 0.7)
					(thickness 0.15)
				)
				(justify left bottom)
			)
		)
		(property "Datasheet" "https://www.onsemi.com/pdf/datasheet/esd5b5.0st1-d.pdf"
			(at 0 0 90)
			(layer "F.Fab")
			(hide yes)
			(effects
				(font
					(size 1.27 1.27)
					(thickness 0.15)
				)
			)
		)
		(property "Description" "Bidirectional TVS, 30 kV,  SOD-523, 5 V, 32 pF"
			(at 0 0 90)
			(layer "F.Fab")
			(hide yes)
			(effects
				(font
					(size 1.27 1.27)
					(thickness 0.15)
				)
			)
		)
		(property "Author" "Antmicro"
			(at 246.507 -112.903 0)
			(layer "F.Fab")
			(hide yes)
			(effects
				(font
					(size 1 1)
					(thickness 0.15)
				)
			)
		)
		(property "License" "Apache-2.0"
			(at 246.507 -112.903 0)
			(layer "F.Fab")
			(hide yes)
			(effects
				(font
					(size 1 1)
					(thickness 0.15)
				)
			)
		)
		(property "MPN" "ESD5B5.0ST1G"
			(at 246.507 -112.903 0)
			(layer "F.Fab")
			(hide yes)
			(effects
				(font
					(size 1 1)
					(thickness 0.15)
				)
			)
		)
		(property "Manufacturer" "ON Semiconductor"
			(at 246.507 -112.903 0)
			(layer "F.Fab")
			(hide yes)
			(effects
				(font
					(size 1 1)
					(thickness 0.15)
				)
			)
		)
		(sheetname "/Connectors/")
		(sheetfile "connectors.kicad_sch")
		(attr smd)
		(fp_rect
			(start -1 -0.6)
			(end 1 0.6)
			(stroke
				(width 0.05)
				(type solid)
			)
			(fill no)
			(layer "F.CrtYd")
		)
		(fp_line
			(start 0.65 -0.425)
			(end 0.65 0.423)
			(stroke
				(width 0.15)
				(type solid)
			)
			(layer "F.Fab")
		)
		(fp_line
			(start -0.652 -0.425)
			(end 0.65 -0.425)
			(stroke
				(width 0.15)
				(type solid)
			)
			(layer "F.Fab")
		)
		(fp_line
			(start -0.652 0.423)
			(end -0.652 -0.425)
			(stroke
				(width 0.15)
				(type solid)
			)
			(layer "F.Fab")
		)
		(fp_line
			(start -0.652 0.423)
			(end 0.65 0.423)
			(stroke
				(width 0.15)
				(type solid)
			)
			(layer "F.Fab")
		)
		(pad "1" smd roundrect
			(at -0.701 0 90)
			(size 0.5 0.6)
			(layers "F.Cu" "F.Mask" "F.Paste")
			(roundrect_rratio 0.25)
			(net 1 "GND")
			(pinfunction "C")
			(pintype "passive")
		)
		(pad "2" smd roundrect
			(at 0.699 0 90)
			(size 0.5 0.6)
			(layers "F.Cu" "F.Mask" "F.Paste")
			(roundrect_rratio 0.25)
			(net 45 "/Connectors/SCL_CAM")
			(pinfunction "A")
			(pintype "passive")
		)
	)
	(footprint "antmicro-footprints:L_Coilcraft-PFL1609"
		(layer "F.Cu")
		(at 163.02 53.594)
		(property "Reference" "L16"
			(at -1.476 1.397 0)
			(layer "F.SilkS")
			(effects
				(font
					(size 0.7 0.7)
					(thickness 0.15)
				)
				(justify left bottom)
			)
		)
		(property "Value" "L_470n_1A_Coilcraft-PFL1609"
			(at 0 2 0)
			(layer "F.Fab")
			(effects
				(font
					(size 0.7 0.7)
					(thickness 0.15)
				)
				(justify left bottom)
			)
		)
		(property "Datasheet" "https://www.coilcraft.com/getmedia/2f4cd442-d64d-4413-a518-12fcfd03318d/pfl1609.pdf"
			(at 0 0 0)
			(layer "F.Fab")
			(hide yes)
			(effects
				(font
					(size 1.27 1.27)
					(thickness 0.15)
				)
			)
		)
		(property "Description" "Power Inductor (SMT), 6.8 µH, 9.2 A, Shielded, 12.8 A, XAL7070"
			(at 0 0 0)
			(layer "F.Fab")
			(hide yes)
			(effects
				(font
					(size 1.27 1.27)
					(thickness 0.15)
				)
			)
		)
		(property "Author" "Antmicro"
			(at 0 0 0)
			(layer "F.Fab")
			(hide yes)
			(effects
				(font
					(size 1 1)
					(thickness 0.15)
				)
			)
		)
		(property "IMax" "1 A"
			(at 0 0 0)
			(layer "F.Fab")
			(hide yes)
			(effects
				(font
					(size 1 1)
					(thickness 0.15)
				)
			)
		)
		(property "ISat" "0.99 A"
			(at 0 0 0)
			(layer "F.Fab")
			(hide yes)
			(effects
				(font
					(size 1 1)
					(thickness 0.15)
				)
			)
		)
		(property "License" "Apache-2.0"
			(at 0 0 0)
			(layer "F.Fab")
			(hide yes)
			(effects
				(font
					(size 1 1)
					(thickness 0.15)
				)
			)
		)
		(property "MPN" "PFL1609-471"
			(at 0 0 0)
			(layer "F.Fab")
			(hide yes)
			(effects
				(font
					(size 1 1)
					(thickness 0.15)
				)
			)
		)
		(property "Manufacturer" "Coilcraft"
			(at 0 0 0)
			(layer "F.Fab")
			(hide yes)
			(effects
				(font
					(size 1 1)
					(thickness 0.15)
				)
			)
		)
		(property "Size" "1.07x1.8"
			(at 0 0 0)
			(layer "F.Fab")
			(hide yes)
			(effects
				(font
					(size 1 1)
					(thickness 0.15)
				)
			)
		)
		(property "Val" "470n/0.99A"
			(at 0 0 0)
			(layer "F.Fab")
			(hide yes)
			(effects
				(font
					(size 1 1)
					(thickness 0.15)
				)
			)
		)
		(sheetname "/Power/")
		(sheetfile "power.kicad_sch")
		(attr smd)
		(fp_line
			(start -0.23 -0.45)
			(end 0.23 -0.45)
			(stroke
				(width 0.15)
				(type solid)
			)
			(layer "F.SilkS")
		)
		(fp_line
			(start -0.23 0.45)
			(end 0.23 0.45)
			(stroke
				(width 0.15)
				(type solid)
			)
			(layer "F.SilkS")
		)
		(fp_rect
			(start -1.2 -0.84)
			(end 1.2 0.84)
			(stroke
				(width 0.05)
				(type solid)
			)
			(fill no)
			(layer "F.CrtYd")
		)
		(fp_rect
			(start -0.9 -0.535)
			(end 0.9 0.535)
			(stroke
				(width 0.15)
				(type solid)
			)
			(fill no)
			(layer "F.Fab")
		)
		(pad "1" smd roundrect
			(at -0.635 0)
			(size 0.64 1.02)
			(layers "F.Cu" "F.Mask" "F.Paste")
			(roundrect_rratio 0.15)
			(net 62 "Net-(L12-Pad2)")
			(pintype "passive")
		)
		(pad "2" smd roundrect
			(at 0.635 0)
			(size 0.64 1.02)
			(layers "F.Cu" "F.Mask" "F.Paste")
			(roundrect_rratio 0.15)
			(net 117 "/Connectors/PoCD")
			(pintype "passive")
		)
	)
	(footprint "antmicro-footprints:C_0603_1608Metric"
		(layer "F.Cu")
		(at 126.674 83.162 90)
		(descr "Capacitor SMD 0603")
		(tags "capacitor 0603")
		(property "Reference" "C18"
			(at -0.5564 2.2056 90)
			(layer "F.SilkS")
			(effects
				(font
					(size 0.7 0.7)
					(thickness 0.15)
				)
				(justify left bottom)
			)
		)
		(property "Value" "C_10u_25V_0603"
			(at -1.42757 1.770288 90)
			(layer "F.Fab")
			(effects
				(font
					(size 0.7 0.7)
					(thickness 0.15)
				)
				(justify left bottom)
			)
		)
		(property "Datasheet" "https://product.tdk.com/en/search/capacitor/ceramic/mlcc/info?part_no=C1608X5R1E106M080AC"
			(at 0 0 90)
			(layer "F.Fab")
			(hide yes)
			(effects
				(font
					(size 1.27 1.27)
					(thickness 0.15)
				)
			)
		)
		(property "Description" "SMD Multilayer Ceramic Capacitor, 10 µF, 25 V, 0603 [1608 Metric], ± 20%, X5R, C"
			(at 0 0 90)
			(layer "F.Fab")
			(hide yes)
			(effects
				(font
					(size 1.27 1.27)
					(thickness 0.15)
				)
			)
		)
		(property "Author" "Antmicro"
			(at 209.836 -43.512 0)
			(layer "F.Fab")
			(hide yes)
			(effects
				(font
					(size 1 1)
					(thickness 0.15)
				)
			)
		)
		(property "Dielectric" ""
			(at 209.836 -43.512 0)
			(layer "F.Fab")
			(hide yes)
			(effects
				(font
					(size 1 1)
					(thickness 0.15)
				)
			)
		)
		(property "License" "Apache-2.0"
			(at 209.836 -43.512 0)
			(layer "F.Fab")
			(hide yes)
			(effects
				(font
					(size 1 1)
					(thickness 0.15)
				)
			)
		)
		(property "MPN" "C1608X5R1E106M080AC"
			(at 209.836 -43.512 0)
			(layer "F.Fab")
			(hide yes)
			(effects
				(font
					(size 1 1)
					(thickness 0.15)
				)
			)
		)
		(property "Manufacturer" "TDK"
			(at 209.836 -43.512 0)
			(layer "F.Fab")
			(hide yes)
			(effects
				(font
					(size 1 1)
					(thickness 0.15)
				)
			)
		)
		(property "Val" "10u"
			(at 209.836 -43.512 0)
			(layer "F.Fab")
			(hide yes)
			(effects
				(font
					(size 1 1)
					(thickness 0.15)
				)
			)
		)
		(property "Voltage" "25V"
			(at 209.836 -43.512 0)
			(layer "F.Fab")
			(hide yes)
			(effects
				(font
					(size 1 1)
					(thickness 0.15)
				)
			)
		)
		(sheetname "/Power/")
		(sheetfile "power.kicad_sch")
		(attr smd)
		(fp_line
			(start -0.15 -0.4)
			(end 0.15 -0.4)
			(stroke
				(width 0.15)
				(type solid)
			)
			(layer "F.SilkS")
		)
		(fp_line
			(start -0.15 0.4)
			(end 0.15 0.4)
			(stroke
				(width 0.15)
				(type solid)
			)
			(layer "F.SilkS")
		)
		(fp_rect
			(start -1.25 -0.65)
			(end 1.25 0.65)
			(stroke
				(width 0.05)
				(type solid)
			)
			(fill no)
			(layer "F.CrtYd")
		)
		(fp_rect
			(start -0.8 -0.4)
			(end 0.8 0.4)
			(stroke
				(width 0.15)
				(type solid)
			)
			(fill no)
			(layer "F.Fab")
		)
		(pad "1" smd roundrect
			(at -0.7 0 90)
			(size 0.8 1)
			(layers "F.Cu" "F.Mask" "F.Paste")
			(roundrect_rratio 0.2)
			(net 1 "GND")
			(pintype "passive")
		)
		(pad "2" smd roundrect
			(at 0.7 0 90)
			(size 0.8 1)
			(layers "F.Cu" "F.Mask" "F.Paste")
			(roundrect_rratio 0.2)
			(net 4 "+12V")
			(pintype "passive")
		)
	)
)
